(kicad_pcb
	(version 20260206)
	(generator "pcbnew")
	(generator_version "10.0")
	(general
		(thickness 1.6)
		(legacy_teardrops no)
	)
	(paper "A4")
	(title_block
		(title "Bryce Canyon_SCC_16316-1_OCP.brd")
		(comment 1 "Bryce Canyon / footprints 370-376 of 1561")
	)
	(layers
		(0 "F.Cu" signal "TOP")
		(4 "In1.Cu" signal "L2GND")
		(6 "In2.Cu" signal "L3")
		(8 "In3.Cu" signal "L4VCC")
		(10 "In4.Cu" signal "L5VCC")
		(12 "In5.Cu" signal "L6")
		(14 "In6.Cu" signal "L7GND")
		(2 "B.Cu" signal "BOTTOM")
		(9 "F.Adhes" user "F.Adhesive")
		(11 "B.Adhes" user "B.Adhesive")
		(13 "F.Paste" user "Package Geometry/Pastemask Top")
		(15 "B.Paste" user "Package Geometry/Pastemask Bottom")
		(5 "F.SilkS" user "Ref Des/Silkscreen Top")
		(7 "B.SilkS" user "Ref Des/Silkscreen Bottom")
		(1 "F.Mask" user "Board Geometry/Soldermask Top")
		(3 "B.Mask" user "Board Geometry/Soldermask Bottom")
		(17 "Dwgs.User" user "User.Drawings")
		(19 "Cmts.User" user "User.Comments")
		(21 "Eco1.User" user "User.Eco1")
		(23 "Eco2.User" user "User.Eco2")
		(25 "Edge.Cuts" user "Board Geometry/Outline")
		(27 "Margin" user)
		(31 "F.CrtYd" user "Package Geometry/Place Bound Top")
		(29 "B.CrtYd" user "Package Geometry/Place Bound Bottom")
		(35 "F.Fab" user "Ref Des/Assembly Top")
		(33 "B.Fab" user "Ref Des/Assembly Bottom")
	)
	(footprint ""
		(layer "F.Cu")
		(at 204.5462 -68.326 180)
		(property "Reference" "C350"
			(at 0 0 180)
			(layer "F.SilkS")
			(hide yes)
			(effects
				(font
					(size 1.27 1.27)
				)
			)
		)
		(property "Value" "SCD1U16V2KX-3GP"
			(at 1.1811 -2.7051 180)
			(unlocked yes)
			(layer "F.Fab")
			(hide yes)
			(effects
				(font
					(size 1.016 1.016)
					(thickness 0.1524)
				)
			)
		)
		(property "Device Type" "C402H22"
			(at 1.1811 -4.2291 180)
			(unlocked yes)
			(layer "F.Fab")
			(hide yes)
			(effects
				(font
					(size 1.016 1.016)
					(thickness 0.1524)
				)
			)
		)
		(duplicate_pad_numbers_are_jumpers no)
		(fp_rect
			(start -0.4318 0.9525)
			(end 0.4318 -0.9525)
			(stroke
				(width 0)
				(type default)
			)
			(fill no)
			(layer "F.CrtYd")
		)
		(fp_rect
			(start -0.4318 0.9525)
			(end 0.4318 -0.9525)
			(stroke
				(width 0)
				(type default)
			)
			(fill no)
			(layer "F.Fab")
		)
		(pad "1" smd custom
			(at 0 -0.4445 180)
			(size 0.1524 0.1524)
			(layers "F.Cu" "F.Mask" "F.Paste")
			(net "P3V3")
			(options
				(clearance outline)
				(anchor circle)
			)
			(primitives
				(gr_poly
					(pts
						(arc
							(start 0.3048 -0.2032)
							(mid 0.275042 -0.275042)
							(end 0.2032 -0.3048)
						)
						(arc
							(start -0.2032 -0.3048)
							(mid -0.275042 -0.275042)
							(end -0.3048 -0.2032)
						)
						(arc
							(start -0.3048 0.2032)
							(mid -0.275042 0.275042)
							(end -0.2032 0.3048)
						)
						(arc
							(start 0.2032 0.3048)
							(mid 0.275042 0.275042)
							(end 0.3048 0.2032)
						)
					)
					(width 0)
					(fill yes)
				)
			)
		)
		(pad "2" smd custom
			(at 0 0.4445 180)
			(size 0.1524 0.1524)
			(layers "F.Cu" "F.Mask" "F.Paste")
			(net "GND")
			(options
				(clearance outline)
				(anchor circle)
			)
			(primitives
				(gr_poly
					(pts
						(arc
							(start 0.3048 -0.2032)
							(mid 0.275042 -0.275042)
							(end 0.2032 -0.3048)
						)
						(arc
							(start -0.2032 -0.3048)
							(mid -0.275042 -0.275042)
							(end -0.3048 -0.2032)
						)
						(arc
							(start -0.3048 0.2032)
							(mid -0.275042 0.275042)
							(end -0.2032 0.3048)
						)
						(arc
							(start 0.2032 0.3048)
							(mid 0.275042 0.275042)
							(end 0.3048 0.2032)
						)
					)
					(width 0)
					(fill yes)
				)
			)
		)
	)
	(footprint ""
		(layer "F.Cu")
		(at 68.92671 -80.556354 90)
		(property "Reference" "C557"
			(at 0 0 90)
			(layer "F.SilkS")
			(hide yes)
			(effects
				(font
					(size 1.27 1.27)
				)
			)
		)
		(property "Value" "SCD1U16V2KX-3GP"
			(at 1.1811 -2.7051 90)
			(unlocked yes)
			(layer "F.Fab")
			(hide yes)
			(effects
				(font
					(size 1.016 1.016)
					(thickness 0.1524)
				)
			)
		)
		(property "Device Type" "C402H22"
			(at 1.1811 -4.2291 90)
			(unlocked yes)
			(layer "F.Fab")
			(hide yes)
			(effects
				(font
					(size 1.016 1.016)
					(thickness 0.1524)
				)
			)
		)
		(duplicate_pad_numbers_are_jumpers no)
		(fp_rect
			(start -0.4318 0.9525)
			(end 0.4318 -0.9525)
			(stroke
				(width 0)
				(type default)
			)
			(fill no)
			(layer "F.CrtYd")
		)
		(fp_rect
			(start -0.4318 0.9525)
			(end 0.4318 -0.9525)
			(stroke
				(width 0)
				(type default)
			)
			(fill no)
			(layer "F.Fab")
		)
		(pad "1" smd custom
			(at 0 -0.4445 90)
			(size 0.1524 0.1524)
			(layers "F.Cu" "F.Mask" "F.Paste")
			(net "P1V8_E")
			(options
				(clearance outline)
				(anchor circle)
			)
			(primitives
				(gr_poly
					(pts
						(arc
							(start 0.3048 -0.2032)
							(mid 0.275042 -0.275042)
							(end 0.2032 -0.3048)
						)
						(arc
							(start -0.2032 -0.3048)
							(mid -0.275042 -0.275042)
							(end -0.3048 -0.2032)
						)
						(arc
							(start -0.3048 0.2032)
							(mid -0.275042 0.275042)
							(end -0.2032 0.3048)
						)
						(arc
							(start 0.2032 0.3048)
							(mid 0.275042 0.275042)
							(end 0.3048 0.2032)
						)
					)
					(width 0)
					(fill yes)
				)
			)
		)
		(pad "2" smd custom
			(at 0 0.4445 90)
			(size 0.1524 0.1524)
			(layers "F.Cu" "F.Mask" "F.Paste")
			(net "GND")
			(options
				(clearance outline)
				(anchor circle)
			)
			(primitives
				(gr_poly
					(pts
						(arc
							(start 0.3048 -0.2032)
							(mid 0.275042 -0.275042)
							(end 0.2032 -0.3048)
						)
						(arc
							(start -0.2032 -0.3048)
							(mid -0.275042 -0.275042)
							(end -0.3048 -0.2032)
						)
						(arc
							(start -0.3048 0.2032)
							(mid -0.275042 0.275042)
							(end -0.2032 0.3048)
						)
						(arc
							(start 0.2032 0.3048)
							(mid 0.275042 0.275042)
							(end 0.3048 0.2032)
						)
					)
					(width 0)
					(fill yes)
				)
			)
		)
	)
	(footprint ""
		(layer "F.Cu")
		(at 70.104 -9.652 90)
		(property "Reference" "R90"
			(at 0 0 90)
			(layer "F.SilkS")
			(hide yes)
			(effects
				(font
					(size 1.27 1.27)
				)
			)
		)
		(property "Value" "0R2J-2-GP"
			(at 0.064008 -3.993896 90)
			(unlocked yes)
			(layer "F.Fab")
			(hide yes)
			(effects
				(font
					(size 1.016 1.016)
					(thickness 0.1524)
				)
			)
		)
		(property "Device Type" "R402H16"
			(at 0.064008 -5.517896 90)
			(unlocked yes)
			(layer "F.Fab")
			(hide yes)
			(effects
				(font
					(size 1.016 1.016)
					(thickness 0.1524)
				)
			)
		)
		(duplicate_pad_numbers_are_jumpers no)
		(fp_line
			(start 0.508 -0.9398)
			(end -0.508 -0.9398)
			(stroke
				(width 0.1524)
				(type default)
			)
			(layer "F.SilkS")
		)
		(fp_line
			(start -0.508 -0.9398)
			(end -0.508 0.9398)
			(stroke
				(width 0.1524)
				(type default)
			)
			(layer "F.SilkS")
		)
		(fp_rect
			(start -0.508 0.9398)
			(end 0.508 -0.9398)
			(stroke
				(width 0)
				(type default)
			)
			(fill no)
			(layer "F.CrtYd")
		)
		(fp_rect
			(start -0.508 0.9398)
			(end 0.508 -0.9398)
			(stroke
				(width 0)
				(type default)
			)
			(fill no)
			(layer "F.Fab")
		)
		(pad "1" smd custom
			(at 0 -0.4445 90)
			(size 0.1397 0.1397)
			(layers "F.Cu" "F.Mask" "F.Paste")
			(net "GND")
			(options
				(clearance outline)
				(anchor circle)
			)
			(primitives
				(gr_poly
					(pts
						(arc
							(start -0.1778 -0.2794)
							(mid -0.249642 -0.249642)
							(end -0.2794 -0.1778)
						)
						(arc
							(start -0.2794 0.1778)
							(mid -0.249642 0.249642)
							(end -0.1778 0.2794)
						)
						(arc
							(start 0.1778 0.2794)
							(mid 0.249642 0.249642)
							(end 0.2794 0.1778)
						)
						(arc
							(start 0.2794 -0.1778)
							(mid 0.249642 -0.249642)
							(end 0.1778 -0.2794)
						)
					)
					(width 0)
					(fill yes)
				)
			)
		)
		(pad "2" smd custom
			(at 0 0.4445 90)
			(size 0.1397 0.1397)
			(layers "F.Cu" "F.Mask" "F.Paste")
			(net "SCC_TYPE_1")
			(options
				(clearance outline)
				(anchor circle)
			)
			(primitives
				(gr_poly
					(pts
						(arc
							(start -0.1778 -0.2794)
							(mid -0.249642 -0.249642)
							(end -0.2794 -0.1778)
						)
						(arc
							(start -0.2794 0.1778)
							(mid -0.249642 0.249642)
							(end -0.1778 0.2794)
						)
						(arc
							(start 0.1778 0.2794)
							(mid 0.249642 0.249642)
							(end 0.2794 0.1778)
						)
						(arc
							(start 0.2794 -0.1778)
							(mid 0.249642 -0.249642)
							(end 0.1778 -0.2794)
						)
					)
					(width 0)
					(fill yes)
				)
			)
		)
	)
	(footprint ""
		(layer "F.Cu")
		(at 11.668252 -59.360816 180)
		(property "Reference" "R13"
			(at 0 0 180)
			(layer "F.SilkS")
			(hide yes)
			(effects
				(font
					(size 1.27 1.27)
				)
			)
		)
		(property "Value" "0R2J-2-GP"
			(at 0.064008 -3.993896 180)
			(unlocked yes)
			(layer "F.Fab")
			(hide yes)
			(effects
				(font
					(size 1.016 1.016)
					(thickness 0.1524)
				)
			)
		)
		(property "Device Type" "R402H16"
			(at 0.064008 -5.517896 180)
			(unlocked yes)
			(layer "F.Fab")
			(hide yes)
			(effects
				(font
					(size 1.016 1.016)
					(thickness 0.1524)
				)
			)
		)
		(duplicate_pad_numbers_are_jumpers no)
		(fp_line
			(start 0.508 -0.9398)
			(end -0.508 -0.9398)
			(stroke
				(width 0.1524)
				(type default)
			)
			(layer "F.SilkS")
		)
		(fp_line
			(start -0.508 -0.9398)
			(end -0.508 0.9398)
			(stroke
				(width 0.1524)
				(type default)
			)
			(layer "F.SilkS")
		)
		(fp_rect
			(start -0.508 0.9398)
			(end 0.508 -0.9398)
			(stroke
				(width 0)
				(type default)
			)
			(fill no)
			(layer "F.CrtYd")
		)
		(fp_rect
			(start -0.508 0.9398)
			(end 0.508 -0.9398)
			(stroke
				(width 0)
				(type default)
			)
			(fill no)
			(layer "F.Fab")
		)
		(pad "1" smd custom
			(at 0 -0.4445 180)
			(size 0.1397 0.1397)
			(layers "F.Cu" "F.Mask" "F.Paste")
			(net "HSW_SDA_2")
			(options
				(clearance outline)
				(anchor circle)
			)
			(primitives
				(gr_poly
					(pts
						(arc
							(start -0.1778 -0.2794)
							(mid -0.249642 -0.249642)
							(end -0.2794 -0.1778)
						)
						(arc
							(start -0.2794 0.1778)
							(mid -0.249642 0.249642)
							(end -0.1778 0.2794)
						)
						(arc
							(start 0.1778 0.2794)
							(mid 0.249642 0.249642)
							(end 0.2794 0.1778)
						)
						(arc
							(start 0.2794 -0.1778)
							(mid 0.249642 -0.249642)
							(end 0.1778 -0.2794)
						)
					)
					(width 0)
					(fill yes)
				)
			)
		)
		(pad "2" smd custom
			(at 0 0.4445 180)
			(size 0.1397 0.1397)
			(layers "F.Cu" "F.Mask" "F.Paste")
			(net "I2C_SCC_SDA2")
			(options
				(clearance outline)
				(anchor circle)
			)
			(primitives
				(gr_poly
					(pts
						(arc
							(start -0.1778 -0.2794)
							(mid -0.249642 -0.249642)
							(end -0.2794 -0.1778)
						)
						(arc
							(start -0.2794 0.1778)
							(mid -0.249642 0.249642)
							(end -0.1778 0.2794)
						)
						(arc
							(start 0.1778 0.2794)
							(mid 0.249642 0.249642)
							(end 0.2794 0.1778)
						)
						(arc
							(start 0.2794 -0.1778)
							(mid 0.249642 -0.249642)
							(end 0.1778 -0.2794)
						)
					)
					(width 0)
					(fill yes)
				)
			)
		)
	)
	(footprint ""
		(layer "F.Cu")
		(at 94.615 -86.487 90)
		(property "Reference" "R561"
			(at 0 0 90)
			(layer "F.SilkS")
			(hide yes)
			(effects
				(font
					(size 1.27 1.27)
				)
			)
		)
		(property "Value" "10KR2F-2-GP"
			(at 0.064008 -3.993896 90)
			(unlocked yes)
			(layer "F.Fab")
			(hide yes)
			(effects
				(font
					(size 1.016 1.016)
					(thickness 0.1524)
				)
			)
		)
		(property "Device Type" "R402H16"
			(at 0.064008 -5.517896 90)
			(unlocked yes)
			(layer "F.Fab")
			(hide yes)
			(effects
				(font
					(size 1.016 1.016)
					(thickness 0.1524)
				)
			)
		)
		(duplicate_pad_numbers_are_jumpers no)
		(fp_line
			(start 0.508 -0.9398)
			(end -0.508 -0.9398)
			(stroke
				(width 0.1524)
				(type default)
			)
			(layer "F.SilkS")
		)
		(fp_line
			(start -0.508 -0.9398)
			(end -0.508 0.9398)
			(stroke
				(width 0.1524)
				(type default)
			)
			(layer "F.SilkS")
		)
		(fp_rect
			(start -0.508 0.9398)
			(end 0.508 -0.9398)
			(stroke
				(width 0)
				(type default)
			)
			(fill no)
			(layer "F.CrtYd")
		)
		(fp_rect
			(start -0.508 0.9398)
			(end 0.508 -0.9398)
			(stroke
				(width 0)
				(type default)
			)
			(fill no)
			(layer "F.Fab")
		)
		(pad "1" smd custom
			(at 0 -0.4445 90)
			(size 0.1397 0.1397)
			(layers "F.Cu" "F.Mask" "F.Paste")
			(net "BMC_LOC_HEARTBEAT_LS")
			(options
				(clearance outline)
				(anchor circle)
			)
			(primitives
				(gr_poly
					(pts
						(arc
							(start -0.1778 -0.2794)
							(mid -0.249642 -0.249642)
							(end -0.2794 -0.1778)
						)
						(arc
							(start -0.2794 0.1778)
							(mid -0.249642 0.249642)
							(end -0.1778 0.2794)
						)
						(arc
							(start 0.1778 0.2794)
							(mid 0.249642 0.249642)
							(end 0.2794 0.1778)
						)
						(arc
							(start 0.2794 -0.1778)
							(mid 0.249642 -0.249642)
							(end 0.1778 -0.2794)
						)
					)
					(width 0)
					(fill yes)
				)
			)
		)
		(pad "2" smd custom
			(at 0 0.4445 90)
			(size 0.1397 0.1397)
			(layers "F.Cu" "F.Mask" "F.Paste")
			(net "P1V8_E")
			(options
				(clearance outline)
				(anchor circle)
			)
			(primitives
				(gr_poly
					(pts
						(arc
							(start -0.1778 -0.2794)
							(mid -0.249642 -0.249642)
							(end -0.2794 -0.1778)
						)
						(arc
							(start -0.2794 0.1778)
							(mid -0.249642 0.249642)
							(end -0.1778 0.2794)
						)
						(arc
							(start 0.1778 0.2794)
							(mid 0.249642 0.249642)
							(end 0.2794 0.1778)
						)
						(arc
							(start 0.2794 -0.1778)
							(mid 0.249642 -0.249642)
							(end 0.1778 -0.2794)
						)
					)
					(width 0)
					(fill yes)
				)
			)
		)
	)
	(footprint ""
		(layer "F.Cu")
		(at 11.9126 -94.801182 180)
		(property "Reference" "C560"
			(at 0 0 180)
			(layer "F.SilkS")
			(hide yes)
			(effects
				(font
					(size 1.27 1.27)
				)
			)
		)
		(property "Value" "SCD1U16V2KX-3GP"
			(at 1.1811 -2.7051 180)
			(unlocked yes)
			(layer "F.Fab")
			(hide yes)
			(effects
				(font
					(size 1.016 1.016)
					(thickness 0.1524)
				)
			)
		)
		(property "Device Type" "C402H22"
			(at 1.1811 -4.2291 180)
			(unlocked yes)
			(layer "F.Fab")
			(hide yes)
			(effects
				(font
					(size 1.016 1.016)
					(thickness 0.1524)
				)
			)
		)
		(duplicate_pad_numbers_are_jumpers no)
		(fp_rect
			(start -0.4318 0.9525)
			(end 0.4318 -0.9525)
			(stroke
				(width 0)
				(type default)
			)
			(fill no)
			(layer "F.CrtYd")
		)
		(fp_rect
			(start -0.4318 0.9525)
			(end 0.4318 -0.9525)
			(stroke
				(width 0)
				(type default)
			)
			(fill no)
			(layer "F.Fab")
		)
		(pad "1" smd custom
			(at 0 -0.4445 180)
			(size 0.1524 0.1524)
			(layers "F.Cu" "F.Mask" "F.Paste")
			(net "VREF3")
			(options
				(clearance outline)
				(anchor circle)
			)
			(primitives
				(gr_poly
					(pts
						(arc
							(start 0.3048 -0.2032)
							(mid 0.275042 -0.275042)
							(end 0.2032 -0.3048)
						)
						(arc
							(start -0.2032 -0.3048)
							(mid -0.275042 -0.275042)
							(end -0.3048 -0.2032)
						)
						(arc
							(start -0.3048 0.2032)
							(mid -0.275042 0.275042)
							(end -0.2032 0.3048)
						)
						(arc
							(start 0.2032 0.3048)
							(mid 0.275042 0.275042)
							(end 0.3048 0.2032)
						)
					)
					(width 0)
					(fill yes)
				)
			)
		)
		(pad "2" smd custom
			(at 0 0.4445 180)
			(size 0.1524 0.1524)
			(layers "F.Cu" "F.Mask" "F.Paste")
			(net "GND")
			(options
				(clearance outline)
				(anchor circle)
			)
			(primitives
				(gr_poly
					(pts
						(arc
							(start 0.3048 -0.2032)
							(mid 0.275042 -0.275042)
							(end 0.2032 -0.3048)
						)
						(arc
							(start -0.2032 -0.3048)
							(mid -0.275042 -0.275042)
							(end -0.3048 -0.2032)
						)
						(arc
							(start -0.3048 0.2032)
							(mid -0.275042 0.275042)
							(end -0.2032 0.3048)
						)
						(arc
							(start 0.2032 0.3048)
							(mid 0.275042 0.275042)
							(end 0.3048 0.2032)
						)
					)
					(width 0)
					(fill yes)
				)
			)
		)
	)
	(footprint ""
		(layer "F.Cu")
		(at 173.11116 -107.30484)
		(property "Reference" "C664"
			(at 0 0 0)
			(layer "F.SilkS")
			(hide yes)
			(effects
				(font
					(size 1.27 1.27)
				)
			)
		)
		(property "Value" "SCD1U50V3KX-GP"
			(at 0 -2.8194 0)
			(unlocked yes)
			(layer "F.Fab")
			(hide yes)
			(effects
				(font
					(size 1.016 1.016)
					(thickness 0.1524)
				)
			)
		)
		(property "Device Type" "C603H36"
			(at 0 -4.3434 0)
			(unlocked yes)
			(layer "F.Fab")
			(hide yes)
			(effects
				(font
					(size 1.016 1.016)
					(thickness 0.1524)
				)
			)
		)
		(duplicate_pad_numbers_are_jumpers no)
		(fp_line
			(start 0.508 0)
			(end -0.508 0)
			(stroke
				(width 0.2032)
				(type default)
			)
			(layer "F.SilkS")
		)
		(fp_rect
			(start -0.5842 1.3335)
			(end 0.5842 -1.3335)
			(stroke
				(width 0)
				(type default)
			)
			(fill no)
			(layer "F.CrtYd")
		)
		(fp_rect
			(start -0.5842 1.3335)
			(end 0.5842 -1.3335)
			(stroke
				(width 0)
				(type default)
			)
			(fill no)
			(layer "F.Fab")
		)
		(pad "1" smd custom
			(at 0 -0.762)
			(size 0.2159 0.2159)
			(layers "F.Cu" "F.Mask" "F.Paste")
			(net "P3V3")
			(options
				(clearance outline)
				(anchor circle)
			)
			(primitives
				(gr_poly
					(pts
						(arc
							(start -0.3302 -0.4318)
							(mid -0.402042 -0.402042)
							(end -0.4318 -0.3302)
						)
						(arc
							(start -0.4318 0.3302)
							(mid -0.402042 0.402042)
							(end -0.3302 0.4318)
						)
						(arc
							(start 0.3302 0.4318)
							(mid 0.402042 0.402042)
							(end 0.4318 0.3302)
						)
						(arc
							(start 0.4318 -0.3302)
							(mid 0.402042 -0.402042)
							(end 0.3302 -0.4318)
						)
					)
					(width 0)
					(fill yes)
				)
			)
		)
		(pad "2" smd custom
			(at 0 0.762)
			(size 0.2159 0.2159)
			(layers "F.Cu" "F.Mask" "F.Paste")
			(net "GND")
			(options
				(clearance outline)
				(anchor circle)
			)
			(primitives
				(gr_poly
					(pts
						(arc
							(start -0.3302 -0.4318)
							(mid -0.402042 -0.402042)
							(end -0.4318 -0.3302)
						)
						(arc
							(start -0.4318 0.3302)
							(mid -0.402042 0.402042)
							(end -0.3302 0.4318)
						)
						(arc
							(start 0.3302 0.4318)
							(mid 0.402042 0.402042)
							(end 0.4318 0.3302)
						)
						(arc
							(start 0.4318 -0.3302)
							(mid 0.402042 -0.402042)
							(end 0.3302 -0.4318)
						)
					)
					(width 0)
					(fill yes)
				)
			)
		)
	)
)
